# BASEBOARD_FAB2 (Tioga Pass) — schematic netlist excerpt (pin names and nets, part order shuffled) for the footprints in the layout excerpt that follows; sources: Cadence DE-HDL packaged netlist, KiCad conversion of Wiwynn_Tioga_Pass_MB.brd

C2U10  CAP  0.22UF 16V 10% X7R  pkg 0402  page 107 : A = P3E_CPU0_PE1_PCH_RXN<3> ; B = P3E_CPU0_PE1_SS_RXN<3>
R2M6  RES  1.0K 0.1% CHIP  pkg 0402  page 118 : A = A_KR1_RBIAS ; B = P1V05_PCH_STBY_KR_PLL
C6U6  CAP  4.7UF 6.3V 10% X6S  pkg 0603  page 233 : A = VR_VB_PVPP_GHJ ; B = AGND_PVPP_GHJ

(kicad_pcb
	(version 20260206)
	(generator "pcbnew")
	(generator_version "10.0")
	(general
		(thickness 1.6)
		(legacy_teardrops no)
	)
	(paper "A4")
	(title_block
		(title "Wiwynn_Tioga_Pass_MB.brd")
		(comment 1 "Tioga Pass / footprints 4342-4344 of 4770")
	)
	(layers
		(0 "F.Cu" signal "TOP")
		(4 "In1.Cu" signal "L2GND")
		(6 "In2.Cu" signal "L3")
		(8 "In3.Cu" signal "L4GND")
		(10 "In4.Cu" signal "L5")
		(12 "In5.Cu" signal "L6GND")
		(14 "In6.Cu" signal "L7VCC")
		(16 "In7.Cu" signal "L8VCC")
		(18 "In8.Cu" signal "L9GND")
		(20 "In9.Cu" signal "L10")
		(22 "In10.Cu" signal "L11GND")
		(24 "In11.Cu" signal "L12")
		(26 "In12.Cu" signal "L13GND")
		(2 "B.Cu" signal "BOTTOM")
		(9 "F.Adhes" user "F.Adhesive")
		(11 "B.Adhes" user "B.Adhesive")
		(13 "F.Paste" user "Package Geometry/Pastemask Top")
		(15 "B.Paste" user "Package Geometry/Pastemask Bottom")
		(5 "F.SilkS" user "Ref Des/Silkscreen Top")
		(7 "B.SilkS" user "Ref Des/Silkscreen Bottom")
		(1 "F.Mask" user "Board Geometry/Soldermask Top")
		(3 "B.Mask" user "Board Geometry/Soldermask Bottom")
		(17 "Dwgs.User" user "User.Drawings")
		(19 "Cmts.User" user "User.Comments")
		(21 "Eco1.User" user "User.Eco1")
		(23 "Eco2.User" user "User.Eco2")
		(25 "Edge.Cuts" user "Board Geometry/Outline")
		(27 "Margin" user)
		(31 "F.CrtYd" user "Package Geometry/Place Bound Top")
		(29 "B.CrtYd" user "Package Geometry/Place Bound Bottom")
		(35 "F.Fab" user "Ref Des/Assembly Top")
		(33 "B.Fab" user "Ref Des/Assembly Bottom")
	)
	(footprint ""
		(layer "B.Cu")
		(at 343.125806 -61.257434)
		(property "Reference" "C2U10"
			(at 0 0 0)
			(layer "B.SilkS")
			(hide yes)
			(effects
				(font
					(size 1.27 1.27)
				)
				(justify mirror)
			)
		)
		(property "Value" ""
			(at 0 0 0)
			(layer "B.Fab")
			(effects
				(font
					(size 1.27 1.27)
				)
				(justify mirror)
			)
		)
		(duplicate_pad_numbers_are_jumpers no)
		(fp_poly
			(pts
				(xy -0.3048 -0.1016) (xy -0.3048 0.9906) (xy 0.3048 0.9906) (xy 0.3048 -0.1016)
			)
			(stroke
				(width 0)
				(type default)
			)
			(fill no)
			(layer "B.CrtYd")
		)
		(fp_line
			(start -0.3048 -0.1016)
			(end 0.3048 -0.1016)
			(stroke
				(width 0.1)
				(type default)
			)
			(layer "B.Fab")
		)
		(fp_line
			(start -0.3048 0.9906)
			(end -0.3048 -0.1016)
			(stroke
				(width 0.1)
				(type default)
			)
			(layer "B.Fab")
		)
		(fp_line
			(start 0.3048 -0.1016)
			(end 0.3048 0.9906)
			(stroke
				(width 0.1)
				(type default)
			)
			(layer "B.Fab")
		)
		(fp_line
			(start 0.3048 0.9906)
			(end -0.3048 0.9906)
			(stroke
				(width 0.1)
				(type default)
			)
			(layer "B.Fab")
		)
		(pad "1" smd rect
			(at 0 0 180)
			(size 0.508 0.508)
			(layers "B.Cu" "B.Mask" "B.Paste")
			(net "P3E_CPU0_PE1_PCH_RXN<3>")
		)
		(pad "2" smd rect
			(at 0 0.889 180)
			(size 0.508 0.508)
			(layers "B.Cu" "B.Mask" "B.Paste")
			(net "P3E_CPU0_PE1_SS_RXN<3>")
		)
		(zone
			(layer "B.Cu")
			(hatch none 0.5)
			(connect_pads
				(clearance 0)
			)
			(min_thickness 0.25)
			(keepout
				(tracks allowed)
				(vias not_allowed)
				(pads allowed)
				(copperpour not_allowed)
				(footprints allowed)
			)
			(placement
				(enabled no)
				(sheetname "")
			)
			(fill
				(thermal_gap 0.5)
				(thermal_bridge_width 0.5)
				(island_removal_mode 0)
			)
			(polygon
				(pts
					(xy 343.379806 -61.003434) (xy 342.871806 -61.003434) (xy 342.871806 -60.622434) (xy 343.379806 -60.622434)
				)
			)
		)
		(zone
			(layer "B.Cu")
			(hatch none 0.5)
			(connect_pads
				(clearance 0)
			)
			(min_thickness 0.25)
			(keepout
				(tracks not_allowed)
				(vias allowed)
				(pads allowed)
				(copperpour not_allowed)
				(footprints allowed)
			)
			(placement
				(enabled no)
				(sheetname "")
			)
			(fill
				(thermal_gap 0.5)
				(thermal_bridge_width 0.5)
				(island_removal_mode 0)
			)
			(polygon
				(pts
					(xy 343.379806 -60.622434) (xy 342.871806 -60.622434) (xy 342.871806 -61.003434) (xy 343.379806 -61.003434)
				)
			)
		)
	)
	(footprint ""
		(layer "B.Cu")
		(at 392.835384 -113.080038)
		(property "Reference" "R2M6"
			(at 0 0 0)
			(layer "B.SilkS")
			(hide yes)
			(effects
				(font
					(size 1.27 1.27)
				)
				(justify mirror)
			)
		)
		(property "Value" ""
			(at 0 0 0)
			(layer "B.Fab")
			(effects
				(font
					(size 1.27 1.27)
				)
				(justify mirror)
			)
		)
		(duplicate_pad_numbers_are_jumpers no)
		(fp_poly
			(pts
				(xy 0.2794 -0.1016) (xy -0.2794 -0.1016) (xy -0.2794 0.9906) (xy 0.2794 0.9906)
			)
			(stroke
				(width 0)
				(type default)
			)
			(fill no)
			(layer "B.CrtYd")
		)
		(fp_line
			(start -0.2794 -0.1016)
			(end 0.2794 -0.1016)
			(stroke
				(width 0.1)
				(type default)
			)
			(layer "B.Fab")
		)
		(fp_line
			(start -0.2794 0.9906)
			(end -0.2794 -0.1016)
			(stroke
				(width 0.1)
				(type default)
			)
			(layer "B.Fab")
		)
		(fp_line
			(start 0.2794 -0.1016)
			(end 0.2794 0.9906)
			(stroke
				(width 0.1)
				(type default)
			)
			(layer "B.Fab")
		)
		(fp_line
			(start 0.2794 0.9906)
			(end -0.2794 0.9906)
			(stroke
				(width 0.1)
				(type default)
			)
			(layer "B.Fab")
		)
		(pad "1" smd rect
			(at 0 0 180)
			(size 0.508 0.508)
			(layers "B.Cu" "B.Mask" "B.Paste")
			(net "A_KR1_RBIAS")
		)
		(pad "2" smd rect
			(at 0 0.889 180)
			(size 0.508 0.508)
			(layers "B.Cu" "B.Mask" "B.Paste")
			(net "P1V05_PCH_STBY_KR_PLL")
		)
		(zone
			(layer "B.Cu")
			(hatch none 0.5)
			(connect_pads
				(clearance 0)
			)
			(min_thickness 0.25)
			(keepout
				(tracks allowed)
				(vias not_allowed)
				(pads allowed)
				(copperpour not_allowed)
				(footprints allowed)
			)
			(placement
				(enabled no)
				(sheetname "")
			)
			(fill
				(thermal_gap 0.5)
				(thermal_bridge_width 0.5)
				(island_removal_mode 0)
			)
			(polygon
				(pts
					(xy 393.089384 -112.826038) (xy 392.581384 -112.826038) (xy 392.581384 -112.445038) (xy 393.089384 -112.445038)
				)
			)
		)
		(zone
			(layer "B.Cu")
			(hatch none 0.5)
			(connect_pads
				(clearance 0)
			)
			(min_thickness 0.25)
			(keepout
				(tracks not_allowed)
				(vias allowed)
				(pads allowed)
				(copperpour not_allowed)
				(footprints allowed)
			)
			(placement
				(enabled no)
				(sheetname "")
			)
			(fill
				(thermal_gap 0.5)
				(thermal_bridge_width 0.5)
				(island_removal_mode 0)
			)
			(polygon
				(pts
					(xy 393.089384 -112.445038) (xy 392.581384 -112.445038) (xy 392.581384 -112.826038) (xy 393.089384 -112.826038)
				)
			)
		)
	)
	(footprint ""
		(layer "B.Cu")
		(at 172.8724 -12.1412)
		(property "Reference" "C6U6"
			(at 0 0 0)
			(layer "B.SilkS")
			(hide yes)
			(effects
				(font
					(size 1.27 1.27)
				)
				(justify mirror)
			)
		)
		(property "Value" ""
			(at 0 0 0)
			(layer "B.Fab")
			(effects
				(font
					(size 1.27 1.27)
				)
				(justify mirror)
			)
		)
		(duplicate_pad_numbers_are_jumpers no)
		(fp_rect
			(start 0.4953 1.6002)
			(end -0.4953 -0.2032)
			(stroke
				(width 0)
				(type default)
			)
			(fill no)
			(layer "B.CrtYd")
		)
		(fp_line
			(start -0.4953 -0.2032)
			(end -0.4953 1.6002)
			(stroke
				(width 0.1)
				(type default)
			)
			(layer "B.Fab")
		)
		(fp_line
			(start -0.4953 1.6002)
			(end 0.4953 1.6002)
			(stroke
				(width 0.1)
				(type default)
			)
			(layer "B.Fab")
		)
		(fp_line
			(start 0.4953 -0.2032)
			(end -0.4953 -0.2032)
			(stroke
				(width 0.1)
				(type default)
			)
			(layer "B.Fab")
		)
		(fp_line
			(start 0.4953 1.6002)
			(end 0.4953 -0.2032)
			(stroke
				(width 0.1)
				(type default)
			)
			(layer "B.Fab")
		)
		(pad "1" smd rect
			(at 0 0 180)
			(size 0.762 0.889)
			(layers "B.Cu" "B.Mask" "B.Paste")
			(net "VR_VB_PVPP_GHJ")
		)
		(pad "2" smd rect
			(at 0 1.397 180)
			(size 0.762 0.889)
			(layers "B.Cu" "B.Mask" "B.Paste")
			(net "AGND_PVPP_GHJ")
		)
		(zone
			(layer "B.Cu")
			(hatch none 0.5)
			(connect_pads
				(clearance 0)
			)
			(min_thickness 0.25)
			(keepout
				(tracks not_allowed)
				(vias allowed)
				(pads allowed)
				(copperpour not_allowed)
				(footprints allowed)
			)
			(placement
				(enabled no)
				(sheetname "")
			)
			(fill
				(thermal_gap 0.5)
				(thermal_bridge_width 0.5)
				(island_removal_mode 0)
			)
			(polygon
				(pts
					(xy 173.2534 -11.1887) (xy 173.2534 -11.6967) (xy 172.4914 -11.6967) (xy 172.4914 -11.1887)
				)
			)
		)
	)
)
